# S9S_MB_2U (Grand Teton) — schematic netlist excerpt (pin names and nets, part order shuffled) for the footprints in the layout excerpt that follows; sources: Cadence DE-HDL packaged netlist, KiCad conversion of 03242023_DA0F0TMBIJ0_F0T_Motherboard_J_brd_V01_OCP.brd

R3488  Q_RES  4.7K 5% CHIP  pkg 0402LF  page 150 : A = P3V3_AUX ; B = GPU_FPGA_EROT_RST_N
R4742  Q_RES  0 5% CHIP  pkg 0402LF  page 227 : A = PRSNT_CABLE_GPU_A1_ISO_N ; B = PRSNT_CABLE_GPU_A1_ISO_R1_N

(kicad_pcb
	(version 20260206)
	(generator "pcbnew")
	(generator_version "10.0")
	(general
		(thickness 1.6)
		(legacy_teardrops no)
	)
	(paper "A4")
	(title_block
		(title "03242023_DA0F0TMBIJ0_F0T_Motherboard_J_brd_V01_OCP.brd")
		(comment 1 "Grand Teton / footprints 3997-3998 of 6105")
	)
	(layers
		(0 "F.Cu" signal "TOP")
		(4 "In1.Cu" signal "GND")
		(6 "In2.Cu" signal "IN1")
		(8 "In3.Cu" signal "GND1")
		(10 "In4.Cu" signal "IN2")
		(12 "In5.Cu" signal "GND2")
		(14 "In6.Cu" signal "IN3")
		(16 "In7.Cu" signal "GND3")
		(18 "In8.Cu" signal "VCC")
		(20 "In9.Cu" signal "VCC1")
		(22 "In10.Cu" signal "GND4")
		(24 "In11.Cu" signal "IN4")
		(26 "In12.Cu" signal "GND5")
		(28 "In13.Cu" signal "IN5")
		(30 "In14.Cu" signal "GND6")
		(32 "In15.Cu" signal "IN6")
		(34 "In16.Cu" signal "GND7")
		(2 "B.Cu" signal "BOTTOM")
		(9 "F.Adhes" user "F.Adhesive")
		(11 "B.Adhes" user "B.Adhesive")
		(13 "F.Paste" user "Package Geometry/Pastemask Top")
		(15 "B.Paste" user "Package Geometry/Pastemask Bottom")
		(5 "F.SilkS" user "Ref Des/Silkscreen Top")
		(7 "B.SilkS" user "Ref Des/Silkscreen Bottom")
		(1 "F.Mask" user "Board Geometry/Soldermask Top")
		(3 "B.Mask" user "Board Geometry/Soldermask Bottom")
		(17 "Dwgs.User" user "User.Drawings")
		(19 "Cmts.User" user "User.Comments")
		(21 "Eco1.User" user "User.Eco1")
		(23 "Eco2.User" user "User.Eco2")
		(25 "Edge.Cuts" user "Board Geometry/Outline")
		(27 "Margin" user)
		(31 "F.CrtYd" user "Package Geometry/Place Bound Top")
		(29 "B.CrtYd" user "Package Geometry/Place Bound Bottom")
		(35 "F.Fab" user "Ref Des/Assembly Top")
		(33 "B.Fab" user "Ref Des/Assembly Bottom")
	)
	(footprint ""
		(layer "F.Cu")
		(at 109.580934 -394.15974 180)
		(property "Reference" "R3488"
			(at 0 0 180)
			(layer "F.SilkS")
			(hide yes)
			(effects
				(font
					(size 1.27 1.27)
				)
			)
		)
		(property "Value" ""
			(at 0 0 180)
			(layer "F.Fab")
			(effects
				(font
					(size 1.27 1.27)
				)
			)
		)
		(duplicate_pad_numbers_are_jumpers no)
		(fp_line
			(start 0.7874 0.4064)
			(end -0.7874 0.4064)
			(stroke
				(width 0.1524)
				(type default)
			)
			(layer "F.SilkS")
		)
		(fp_line
			(start 0.7874 -0.4064)
			(end 0.7874 0.4064)
			(stroke
				(width 0.1524)
				(type default)
			)
			(layer "F.SilkS")
		)
		(fp_line
			(start -0.7874 0.4064)
			(end -0.7874 -0.4064)
			(stroke
				(width 0.1524)
				(type default)
			)
			(layer "F.SilkS")
		)
		(fp_line
			(start -0.7874 -0.4064)
			(end 0.7874 -0.4064)
			(stroke
				(width 0.1524)
				(type default)
			)
			(layer "F.SilkS")
		)
		(fp_line
			(start 0.67945 0.3048)
			(end 0.120396 0.3048)
			(stroke
				(width 0.1)
				(type default)
			)
			(layer "F.Fab")
		)
		(fp_line
			(start 0.67945 -0.3048)
			(end 0.67945 0.3048)
			(stroke
				(width 0.1)
				(type default)
			)
			(layer "F.Fab")
		)
		(fp_line
			(start 0.12065 -0.2794)
			(end 0.12065 -0.3048)
			(stroke
				(width 0.1)
				(type default)
			)
			(layer "F.Fab")
		)
		(fp_line
			(start 0.12065 -0.3048)
			(end 0.67945 -0.3048)
			(stroke
				(width 0.1)
				(type default)
			)
			(layer "F.Fab")
		)
		(fp_line
			(start 0.120396 0.3048)
			(end 0.120396 0.2794)
			(stroke
				(width 0.1)
				(type default)
			)
			(layer "F.Fab")
		)
		(fp_line
			(start 0.120396 0.2794)
			(end -0.12065 0.2794)
			(stroke
				(width 0.1)
				(type default)
			)
			(layer "F.Fab")
		)
		(fp_line
			(start -0.12065 0.3048)
			(end -0.67945 0.3048)
			(stroke
				(width 0.1)
				(type default)
			)
			(layer "F.Fab")
		)
		(fp_line
			(start -0.12065 0.2794)
			(end -0.12065 0.3048)
			(stroke
				(width 0.1)
				(type default)
			)
			(layer "F.Fab")
		)
		(fp_line
			(start -0.12065 -0.2794)
			(end 0.12065 -0.2794)
			(stroke
				(width 0.1)
				(type default)
			)
			(layer "F.Fab")
		)
		(fp_line
			(start -0.12065 -0.305054)
			(end -0.12065 -0.2794)
			(stroke
				(width 0.1)
				(type default)
			)
			(layer "F.Fab")
		)
		(fp_line
			(start -0.67945 0.3048)
			(end -0.67945 -0.305054)
			(stroke
				(width 0.1)
				(type default)
			)
			(layer "F.Fab")
		)
		(fp_line
			(start -0.67945 -0.305054)
			(end -0.12065 -0.305054)
			(stroke
				(width 0.1)
				(type default)
			)
			(layer "F.Fab")
		)
		(pad "1" smd circle
			(at -0.40005 0 180)
			(size 0 0)
			(layers "F.Cu" "F.Mask" "F.Paste")
			(net "P3V3_AUX")
		)
		(pad "2" smd circle
			(at 0.40005 0 180)
			(size 0 0)
			(layers "F.Cu" "F.Mask" "F.Paste")
			(net "GPU_FPGA_EROT_RST_N")
		)
	)
	(footprint ""
		(layer "F.Cu")
		(at 16.51 -426.1358 -90)
		(property "Reference" "R4742"
			(at 0 0 270)
			(layer "F.SilkS")
			(hide yes)
			(effects
				(font
					(size 1.27 1.27)
				)
			)
		)
		(property "Value" ""
			(at 0 0 270)
			(layer "F.Fab")
			(effects
				(font
					(size 1.27 1.27)
				)
			)
		)
		(duplicate_pad_numbers_are_jumpers no)
		(fp_line
			(start -0.7874 0.4064)
			(end -0.7874 -0.4064)
			(stroke
				(width 0.1524)
				(type default)
			)
			(layer "F.SilkS")
		)
		(fp_line
			(start 0.7874 0.4064)
			(end -0.7874 0.4064)
			(stroke
				(width 0.1524)
				(type default)
			)
			(layer "F.SilkS")
		)
		(fp_line
			(start -0.7874 -0.4064)
			(end 0.7874 -0.4064)
			(stroke
				(width 0.1524)
				(type default)
			)
			(layer "F.SilkS")
		)
		(fp_line
			(start 0.7874 -0.4064)
			(end 0.7874 0.4064)
			(stroke
				(width 0.1524)
				(type default)
			)
			(layer "F.SilkS")
		)
		(fp_line
			(start -0.67945 0.3048)
			(end -0.67945 -0.305054)
			(stroke
				(width 0.1)
				(type default)
			)
			(layer "F.Fab")
		)
		(fp_line
			(start -0.12065 0.3048)
			(end -0.67945 0.3048)
			(stroke
				(width 0.1)
				(type default)
			)
			(layer "F.Fab")
		)
		(fp_line
			(start 0.120396 0.3048)
			(end 0.120396 0.2794)
			(stroke
				(width 0.1)
				(type default)
			)
			(layer "F.Fab")
		)
		(fp_line
			(start 0.67945 0.3048)
			(end 0.120396 0.3048)
			(stroke
				(width 0.1)
				(type default)
			)
			(layer "F.Fab")
		)
		(fp_line
			(start -0.12065 0.2794)
			(end -0.12065 0.3048)
			(stroke
				(width 0.1)
				(type default)
			)
			(layer "F.Fab")
		)
		(fp_line
			(start 0.120396 0.2794)
			(end -0.12065 0.2794)
			(stroke
				(width 0.1)
				(type default)
			)
			(layer "F.Fab")
		)
		(fp_line
			(start -0.12065 -0.2794)
			(end 0.12065 -0.2794)
			(stroke
				(width 0.1)
				(type default)
			)
			(layer "F.Fab")
		)
		(fp_line
			(start 0.12065 -0.2794)
			(end 0.12065 -0.3048)
			(stroke
				(width 0.1)
				(type default)
			)
			(layer "F.Fab")
		)
		(fp_line
			(start 0.12065 -0.3048)
			(end 0.67945 -0.3048)
			(stroke
				(width 0.1)
				(type default)
			)
			(layer "F.Fab")
		)
		(fp_line
			(start 0.67945 -0.3048)
			(end 0.67945 0.3048)
			(stroke
				(width 0.1)
				(type default)
			)
			(layer "F.Fab")
		)
		(fp_line
			(start -0.67945 -0.305054)
			(end -0.12065 -0.305054)
			(stroke
				(width 0.1)
				(type default)
			)
			(layer "F.Fab")
		)
		(fp_line
			(start -0.12065 -0.305054)
			(end -0.12065 -0.2794)
			(stroke
				(width 0.1)
				(type default)
			)
			(layer "F.Fab")
		)
		(pad "1" smd circle
			(at -0.40005 0 270)
			(size 0 0)
			(layers "F.Cu" "F.Mask" "F.Paste")
			(net "PRSNT_CABLE_GPU_A1_ISO_N")
		)
		(pad "2" smd circle
			(at 0.40005 0 270)
			(size 0 0)
			(layers "F.Cu" "F.Mask" "F.Paste")
			(net "PRSNT_CABLE_GPU_A1_ISO_R1_N")
		)
	)
)
